# BASEBOARD_FAB2 (Tioga Pass) — schematic netlist excerpt (pin names and nets, part order shuffled) for the footprints in the layout excerpt that follows; sources: Cadence DE-HDL packaged netlist, KiCad conversion of Wiwynn_Tioga_Pass_MB.brd

C4D45  CAP  220PF 50V 10% X7R  pkg 0402LF  page 201 : A = VSENSE_PVCCIN_CPU0_AVSP ; B = VSENSE_PVCCIN_CPU0_N
R6F1  RES  49.9 1% CHIP  pkg 0402  page 89 : A = IRQ_DIMM_SAVE_N ; B = FM_ADR_COMPLETE_DEF_N

(kicad_pcb
	(version 20260206)
	(generator "pcbnew")
	(generator_version "10.0")
	(general
		(thickness 1.6)
		(legacy_teardrops no)
	)
	(paper "A4")
	(title_block
		(title "Wiwynn_Tioga_Pass_MB.brd")
		(comment 1 "Tioga Pass / footprints 2294-2295 of 4770")
	)
	(layers
		(0 "F.Cu" signal "TOP")
		(4 "In1.Cu" signal "L2GND")
		(6 "In2.Cu" signal "L3")
		(8 "In3.Cu" signal "L4GND")
		(10 "In4.Cu" signal "L5")
		(12 "In5.Cu" signal "L6GND")
		(14 "In6.Cu" signal "L7VCC")
		(16 "In7.Cu" signal "L8VCC")
		(18 "In8.Cu" signal "L9GND")
		(20 "In9.Cu" signal "L10")
		(22 "In10.Cu" signal "L11GND")
		(24 "In11.Cu" signal "L12")
		(26 "In12.Cu" signal "L13GND")
		(2 "B.Cu" signal "BOTTOM")
		(9 "F.Adhes" user "F.Adhesive")
		(11 "B.Adhes" user "B.Adhesive")
		(13 "F.Paste" user "Package Geometry/Pastemask Top")
		(15 "B.Paste" user "Package Geometry/Pastemask Bottom")
		(5 "F.SilkS" user "Ref Des/Silkscreen Top")
		(7 "B.SilkS" user "Ref Des/Silkscreen Bottom")
		(1 "F.Mask" user "Board Geometry/Soldermask Top")
		(3 "B.Mask" user "Board Geometry/Soldermask Bottom")
		(17 "Dwgs.User" user "User.Drawings")
		(19 "Cmts.User" user "User.Comments")
		(21 "Eco1.User" user "User.Eco1")
		(23 "Eco2.User" user "User.Eco2")
		(25 "Edge.Cuts" user "Board Geometry/Outline")
		(27 "Margin" user)
		(31 "F.CrtYd" user "Package Geometry/Place Bound Top")
		(29 "B.CrtYd" user "Package Geometry/Place Bound Bottom")
		(35 "F.Fab" user "Ref Des/Assembly Top")
		(33 "B.Fab" user "Ref Des/Assembly Bottom")
	)
	(footprint ""
		(layer "F.Cu")
		(at 186.309 -64.77 90)
		(property "Reference" "C4D45"
			(at 0 0 90)
			(layer "F.SilkS")
			(hide yes)
			(effects
				(font
					(size 1.27 1.27)
				)
			)
		)
		(property "Value" ""
			(at 0 0 90)
			(layer "F.Fab")
			(effects
				(font
					(size 1.27 1.27)
				)
			)
		)
		(duplicate_pad_numbers_are_jumpers no)
		(fp_rect
			(start -0.3048 -0.1016)
			(end 0.3048 0.9906)
			(stroke
				(width 0)
				(type default)
			)
			(fill no)
			(layer "F.CrtYd")
		)
		(fp_line
			(start 0.3048 -0.1016)
			(end -0.3048 -0.1016)
			(stroke
				(width 0.1)
				(type default)
			)
			(layer "F.Fab")
		)
		(fp_line
			(start -0.3048 -0.1016)
			(end -0.3048 0.9906)
			(stroke
				(width 0.1)
				(type default)
			)
			(layer "F.Fab")
		)
		(fp_line
			(start 0.3048 0.9906)
			(end 0.3048 -0.1016)
			(stroke
				(width 0.1)
				(type default)
			)
			(layer "F.Fab")
		)
		(fp_line
			(start -0.3048 0.9906)
			(end 0.3048 0.9906)
			(stroke
				(width 0.1)
				(type default)
			)
			(layer "F.Fab")
		)
		(pad "1" smd rect
			(at 0 0 90)
			(size 0.508 0.508)
			(layers "F.Cu" "F.Mask" "F.Paste")
			(net "VSENSE_PVCCIN_CPU0_AVSP")
		)
		(pad "2" smd rect
			(at 0 0.889 90)
			(size 0.508 0.508)
			(layers "F.Cu" "F.Mask" "F.Paste")
			(net "VSENSE_PVCCIN_CPU0_N")
		)
		(zone
			(layer "F.Cu")
			(hatch none 0.5)
			(connect_pads
				(clearance 0)
			)
			(min_thickness 0.25)
			(keepout
				(tracks not_allowed)
				(vias allowed)
				(pads allowed)
				(copperpour not_allowed)
				(footprints allowed)
			)
			(placement
				(enabled no)
				(sheetname "")
			)
			(fill
				(thermal_gap 0.5)
				(thermal_bridge_width 0.5)
				(island_removal_mode 0)
			)
			(polygon
				(pts
					(xy 186.563 -64.516) (xy 186.944 -64.516) (xy 186.944 -65.024) (xy 186.563 -65.024)
				)
			)
		)
		(zone
			(layer "F.Cu")
			(hatch none 0.5)
			(connect_pads
				(clearance 0)
			)
			(min_thickness 0.25)
			(keepout
				(tracks allowed)
				(vias not_allowed)
				(pads allowed)
				(copperpour not_allowed)
				(footprints allowed)
			)
			(placement
				(enabled no)
				(sheetname "")
			)
			(fill
				(thermal_gap 0.5)
				(thermal_bridge_width 0.5)
				(island_removal_mode 0)
			)
			(polygon
				(pts
					(xy 186.563 -64.516) (xy 186.944 -64.516) (xy 186.944 -65.024) (xy 186.563 -65.024)
				)
			)
		)
	)
	(footprint ""
		(layer "F.Cu")
		(at 323.723 -35.814 90)
		(property "Reference" "R6F1"
			(at 0 0 90)
			(layer "F.SilkS")
			(hide yes)
			(effects
				(font
					(size 1.27 1.27)
				)
			)
		)
		(property "Value" ""
			(at 0 0 90)
			(layer "F.Fab")
			(effects
				(font
					(size 1.27 1.27)
				)
			)
		)
		(duplicate_pad_numbers_are_jumpers no)
		(fp_poly
			(pts
				(xy -0.2794 -0.1016) (xy 0.2794 -0.1016) (xy 0.2794 0.9906) (xy -0.2794 0.9906)
			)
			(stroke
				(width 0)
				(type default)
			)
			(fill no)
			(layer "F.CrtYd")
		)
		(fp_line
			(start 0.2794 -0.1016)
			(end -0.2794 -0.1016)
			(stroke
				(width 0.1)
				(type default)
			)
			(layer "F.Fab")
		)
		(fp_line
			(start -0.2794 -0.1016)
			(end -0.2794 0.9906)
			(stroke
				(width 0.1)
				(type default)
			)
			(layer "F.Fab")
		)
		(fp_line
			(start 0.2794 0.9906)
			(end 0.2794 -0.1016)
			(stroke
				(width 0.1)
				(type default)
			)
			(layer "F.Fab")
		)
		(fp_line
			(start -0.2794 0.9906)
			(end 0.2794 0.9906)
			(stroke
				(width 0.1)
				(type default)
			)
			(layer "F.Fab")
		)
		(pad "1" smd rect
			(at 0 0 90)
			(size 0.508 0.508)
			(layers "F.Cu" "F.Mask" "F.Paste")
			(net "IRQ_DIMM_SAVE_N")
		)
		(pad "2" smd rect
			(at 0 0.889 90)
			(size 0.508 0.508)
			(layers "F.Cu" "F.Mask" "F.Paste")
			(net "FM_ADR_COMPLETE_DEF_N")
		)
		(zone
			(layer "F.Cu")
			(hatch none 0.5)
			(connect_pads
				(clearance 0)
			)
			(min_thickness 0.25)
			(keepout
				(tracks allowed)
				(vias not_allowed)
				(pads allowed)
				(copperpour not_allowed)
				(footprints allowed)
			)
			(placement
				(enabled no)
				(sheetname "")
			)
			(fill
				(thermal_gap 0.5)
				(thermal_bridge_width 0.5)
				(island_removal_mode 0)
			)
			(polygon
				(pts
					(xy 323.977 -35.56) (xy 323.977 -36.068) (xy 324.358 -36.068) (xy 324.358 -35.56)
				)
			)
		)
		(zone
			(layer "F.Cu")
			(hatch none 0.5)
			(connect_pads
				(clearance 0)
			)
			(min_thickness 0.25)
			(keepout
				(tracks not_allowed)
				(vias allowed)
				(pads allowed)
				(copperpour not_allowed)
				(footprints allowed)
			)
			(placement
				(enabled no)
				(sheetname "")
			)
			(fill
				(thermal_gap 0.5)
				(thermal_bridge_width 0.5)
				(island_removal_mode 0)
			)
			(polygon
				(pts
					(xy 324.358 -35.56) (xy 324.358 -36.068) (xy 323.977 -36.068) (xy 323.977 -35.56)
				)
			)
		)
	)
)
